(kicad_pcb
	(version 20260206)
	(generator "pcbnew")
	(generator_version "10.0")
	(general
		(thickness 1.6)
		(legacy_teardrops no)
	)
	(paper "A4")
	(title_block
		(title "03242023_DA0F0TMBIJ0_F0T_Motherboard_J_brd_V01_OCP.brd")
		(comment 1 "Grand Teton / footprints 1294-1299 of 6105")
	)
	(layers
		(0 "F.Cu" signal "TOP")
		(4 "In1.Cu" signal "GND")
		(6 "In2.Cu" signal "IN1")
		(8 "In3.Cu" signal "GND1")
		(10 "In4.Cu" signal "IN2")
		(12 "In5.Cu" signal "GND2")
		(14 "In6.Cu" signal "IN3")
		(16 "In7.Cu" signal "GND3")
		(18 "In8.Cu" signal "VCC")
		(20 "In9.Cu" signal "VCC1")
		(22 "In10.Cu" signal "GND4")
		(24 "In11.Cu" signal "IN4")
		(26 "In12.Cu" signal "GND5")
		(28 "In13.Cu" signal "IN5")
		(30 "In14.Cu" signal "GND6")
		(32 "In15.Cu" signal "IN6")
		(34 "In16.Cu" signal "GND7")
		(2 "B.Cu" signal "BOTTOM")
		(9 "F.Adhes" user "F.Adhesive")
		(11 "B.Adhes" user "B.Adhesive")
		(13 "F.Paste" user "Package Geometry/Pastemask Top")
		(15 "B.Paste" user "Package Geometry/Pastemask Bottom")
		(5 "F.SilkS" user "Ref Des/Silkscreen Top")
		(7 "B.SilkS" user "Ref Des/Silkscreen Bottom")
		(1 "F.Mask" user "Board Geometry/Soldermask Top")
		(3 "B.Mask" user "Board Geometry/Soldermask Bottom")
		(17 "Dwgs.User" user "User.Drawings")
		(19 "Cmts.User" user "User.Comments")
		(21 "Eco1.User" user "User.Eco1")
		(23 "Eco2.User" user "User.Eco2")
		(25 "Edge.Cuts" user "Board Geometry/Outline")
		(27 "Margin" user)
		(31 "F.CrtYd" user "Package Geometry/Place Bound Top")
		(29 "B.CrtYd" user "Package Geometry/Place Bound Bottom")
		(35 "F.Fab" user "Ref Des/Assembly Top")
		(33 "B.Fab" user "Ref Des/Assembly Bottom")
	)
	(footprint ""
		(layer "F.Cu")
		(at 61.175646 -111.226346)
		(property "Reference" "U39"
			(at -2.1844 -4.587748 0)
			(unlocked yes)
			(layer "F.SilkS")
			(effects
				(font
					(size 0.7874 0.5842)
					(thickness 0.1524)
				)
				(justify left)
			)
		)
		(property "Value" ""
			(at 0 0 0)
			(layer "F.Fab")
			(effects
				(font
					(size 1.27 1.27)
				)
			)
		)
		(duplicate_pad_numbers_are_jumpers no)
		(fp_line
			(start -1.8542 -3.949954)
			(end -1.8542 3.949954)
			(stroke
				(width 0.1524)
				(type default)
			)
			(layer "F.SilkS")
		)
		(fp_line
			(start -1.8542 3.949954)
			(end 1.8542 3.949954)
			(stroke
				(width 0.1524)
				(type default)
			)
			(layer "F.SilkS")
		)
		(fp_line
			(start -1.282954 -3.949954)
			(end -1.8542 -3.949954)
			(stroke
				(width 0.1524)
				(type default)
			)
			(layer "F.SilkS")
		)
		(fp_line
			(start 0 -2.667)
			(end -1.282954 -3.949954)
			(stroke
				(width 0.1524)
				(type default)
			)
			(layer "F.SilkS")
		)
		(fp_line
			(start 1.282954 -3.949954)
			(end 0 -2.667)
			(stroke
				(width 0.1524)
				(type default)
			)
			(layer "F.SilkS")
		)
		(fp_line
			(start 1.8542 -3.949954)
			(end 1.282954 -3.949954)
			(stroke
				(width 0.1524)
				(type default)
			)
			(layer "F.SilkS")
		)
		(fp_line
			(start 1.8542 3.949954)
			(end 1.8542 -3.949954)
			(stroke
				(width 0.1524)
				(type default)
			)
			(layer "F.SilkS")
		)
		(fp_poly
			(pts
				(xy -4.8006 -4.08305) (xy -4.8006 -3.06705) (xy -3.7846 -3.57505)
			)
			(stroke
				(width 0)
				(type default)
			)
			(fill yes)
			(layer "F.SilkS")
		)
		(fp_line
			(start -2.249932 -3.949954)
			(end -2.249932 3.949954)
			(stroke
				(width 0.1)
				(type default)
			)
			(layer "F.Fab")
		)
		(fp_line
			(start -2.249932 3.949954)
			(end 2.249932 3.949954)
			(stroke
				(width 0.1)
				(type default)
			)
			(layer "F.Fab")
		)
		(fp_line
			(start 2.249932 -3.949954)
			(end -2.249932 -3.949954)
			(stroke
				(width 0.1)
				(type default)
			)
			(layer "F.Fab")
		)
		(fp_line
			(start 2.249932 3.949954)
			(end 2.249932 -3.949954)
			(stroke
				(width 0.1)
				(type default)
			)
			(layer "F.Fab")
		)
		(fp_poly
			(pts
				(xy -4.8006 -4.08305) (xy -4.8006 -3.06705) (xy -3.7846 -3.57505)
			)
			(stroke
				(width 0)
				(type default)
			)
			(fill yes)
			(layer "F.Fab")
		)
		(pad "1" smd rect
			(at -2.800096 -3.57505 270)
			(size 0.3048 1.6002)
			(layers "F.Cu" "F.Mask" "F.Paste")
			(net "PCA9548_PCIE0_ADDR0")
		)
		(pad "2" smd rect
			(at -2.800096 -2.925064 270)
			(size 0.3048 1.6002)
			(layers "F.Cu" "F.Mask" "F.Paste")
			(net "PCA9548_PCIE0_ADDR1")
		)
		(pad "3" smd rect
			(at -2.800096 -2.275078 270)
			(size 0.3048 1.6002)
			(layers "F.Cu" "F.Mask" "F.Paste")
			(net "PU_RST_SMB_PCIE2_N")
		)
		(pad "4" smd rect
			(at -2.800096 -1.625092 270)
			(size 0.3048 1.6002)
			(layers "F.Cu" "F.Mask" "F.Paste")
			(net "SMB_VR_3V3AUX_SDA_R6")
		)
		(pad "5" smd rect
			(at -2.800096 -0.975106 270)
			(size 0.3048 1.6002)
			(layers "F.Cu" "F.Mask" "F.Paste")
			(net "SMB_VR_3V3AUX_SCL_R6")
		)
		(pad "6" smd rect
			(at -2.800096 -0.32512 270)
			(size 0.3048 1.6002)
			(layers "F.Cu" "F.Mask" "F.Paste")
			(net "SMB_LM75_0_3V3AUX_SDA_R")
		)
		(pad "7" smd rect
			(at -2.800096 0.32512 270)
			(size 0.3048 1.6002)
			(layers "F.Cu" "F.Mask" "F.Paste")
			(net "SMB_LM75_0_3V3AUX_SCL_R")
		)
		(pad "8" smd rect
			(at -2.800096 0.975106 270)
			(size 0.3048 1.6002)
			(layers "F.Cu" "F.Mask" "F.Paste")
			(net "SMB_LM75_1_3V3AUX_SDA_R")
		)
		(pad "9" smd rect
			(at -2.800096 1.625092 270)
			(size 0.3048 1.6002)
			(layers "F.Cu" "F.Mask" "F.Paste")
			(net "SMB_LM75_1_3V3AUX_SCL_R")
		)
		(pad "10" smd rect
			(at -2.800096 2.275078 270)
			(size 0.3048 1.6002)
			(layers "F.Cu" "F.Mask" "F.Paste")
			(net "SMB_LM75_2_3V3AUX_SDA_R")
		)
		(pad "11" smd rect
			(at -2.800096 2.925064 270)
			(size 0.3048 1.6002)
			(layers "F.Cu" "F.Mask" "F.Paste")
			(net "SMB_LM75_2_3V3AUX_SCL_R")
		)
		(pad "12" smd rect
			(at -2.800096 3.57505 270)
			(size 0.3048 1.6002)
			(layers "F.Cu" "F.Mask" "F.Paste")
			(net "GND")
		)
		(pad "13" smd rect
			(at 2.800096 3.57505 270)
			(size 0.3048 1.6002)
			(layers "F.Cu" "F.Mask" "F.Paste")
			(net "SMB_LM75_3_3V3AUX_SDA_R")
		)
		(pad "14" smd rect
			(at 2.800096 2.925064 270)
			(size 0.3048 1.6002)
			(layers "F.Cu" "F.Mask" "F.Paste")
			(net "SMB_LM75_3_3V3AUX_SCL_R")
		)
		(pad "15" smd rect
			(at 2.800096 2.275078 270)
			(size 0.3048 1.6002)
			(layers "F.Cu" "F.Mask" "F.Paste")
			(net "Net_8618")
		)
		(pad "16" smd rect
			(at 2.800096 1.625092 270)
			(size 0.3048 1.6002)
			(layers "F.Cu" "F.Mask" "F.Paste")
			(net "Net_8621")
		)
		(pad "17" smd rect
			(at 2.800096 0.975106 270)
			(size 0.3048 1.6002)
			(layers "F.Cu" "F.Mask" "F.Paste")
			(net "Net_8617")
		)
		(pad "18" smd rect
			(at 2.800096 0.32512 270)
			(size 0.3048 1.6002)
			(layers "F.Cu" "F.Mask" "F.Paste")
			(net "Net_8620")
		)
		(pad "19" smd rect
			(at 2.800096 -0.32512 270)
			(size 0.3048 1.6002)
			(layers "F.Cu" "F.Mask" "F.Paste")
			(net "Net_8616")
		)
		(pad "20" smd rect
			(at 2.800096 -0.975106 270)
			(size 0.3048 1.6002)
			(layers "F.Cu" "F.Mask" "F.Paste")
			(net "Net_8619")
		)
		(pad "21" smd rect
			(at 2.800096 -1.625092 270)
			(size 0.3048 1.6002)
			(layers "F.Cu" "F.Mask" "F.Paste")
			(net "PCA9548_PCIE0_ADDR2")
		)
		(pad "22" smd rect
			(at 2.800096 -2.275078 270)
			(size 0.3048 1.6002)
			(layers "F.Cu" "F.Mask" "F.Paste")
			(net "SMB_VR_SENSOR_3V3AUX_SCL_R")
		)
		(pad "23" smd rect
			(at 2.800096 -2.925064 270)
			(size 0.3048 1.6002)
			(layers "F.Cu" "F.Mask" "F.Paste")
			(net "SMB_VR_SENSOR_3V3AUX_SDA_R")
		)
		(pad "24" smd rect
			(at 2.800096 -3.57505 270)
			(size 0.3048 1.6002)
			(layers "F.Cu" "F.Mask" "F.Paste")
			(net "P3V3_AUX")
		)
	)
	(footprint ""
		(layer "F.Cu")
		(at 93.27388 -56.225948)
		(property "Reference" "U87"
			(at -1.4224 -2.327148 0)
			(unlocked yes)
			(layer "F.SilkS")
			(effects
				(font
					(size 0.7874 0.5842)
					(thickness 0.1524)
				)
			)
		)
		(property "Value" ""
			(at 0 0 0)
			(layer "F.Fab")
			(effects
				(font
					(size 1.27 1.27)
				)
			)
		)
		(duplicate_pad_numbers_are_jumpers no)
		(fp_line
			(start -1.949958 -1.610106)
			(end 1.949958 -1.610106)
			(stroke
				(width 0.1524)
				(type default)
			)
			(layer "F.SilkS")
		)
		(fp_line
			(start -1.949958 1.610106)
			(end -1.949958 -1.610106)
			(stroke
				(width 0.1524)
				(type default)
			)
			(layer "F.SilkS")
		)
		(fp_line
			(start 1.949958 -1.560068)
			(end 1.949958 1.610106)
			(stroke
				(width 0.1524)
				(type default)
			)
			(layer "F.SilkS")
		)
		(fp_line
			(start 1.949958 1.610106)
			(end -1.949958 1.610106)
			(stroke
				(width 0.1524)
				(type default)
			)
			(layer "F.SilkS")
		)
		(fp_line
			(start -0.750062 -1.560068)
			(end 0.750062 -1.560068)
			(stroke
				(width 0.1)
				(type default)
			)
			(layer "F.Fab")
		)
		(fp_line
			(start -0.750062 1.560068)
			(end -0.750062 -1.560068)
			(stroke
				(width 0.1)
				(type default)
			)
			(layer "F.Fab")
		)
		(fp_line
			(start 0.750062 -1.560068)
			(end 0.750062 1.560068)
			(stroke
				(width 0.1)
				(type default)
			)
			(layer "F.Fab")
		)
		(fp_line
			(start 0.750062 1.560068)
			(end -0.750062 1.560068)
			(stroke
				(width 0.1)
				(type default)
			)
			(layer "F.Fab")
		)
		(pad "D" smd rect
			(at 1.100074 0 270)
			(size 1.016 1.4224)
			(layers "F.Cu" "F.Mask" "F.Paste")
			(net "P1V05_PCH_AUX")
		)
		(pad "G" smd rect
			(at -1.100074 -0.94996 270)
			(size 1.016 1.4224)
			(layers "F.Cu" "F.Mask" "F.Paste")
			(net "FM_REMOTE_DEBUG_DET_R")
		)
		(pad "S" smd rect
			(at -1.100074 0.94996 270)
			(size 1.016 1.4224)
			(layers "F.Cu" "F.Mask" "F.Paste")
			(net "FM_BMC_EN_DET")
		)
	)
	(footprint ""
		(layer "F.Cu")
		(at 356.616 -416.143948)
		(property "Reference" "R4562"
			(at 0 0 0)
			(layer "F.SilkS")
			(hide yes)
			(effects
				(font
					(size 1.27 1.27)
				)
			)
		)
		(property "Value" ""
			(at 0 0 0)
			(layer "F.Fab")
			(effects
				(font
					(size 1.27 1.27)
				)
			)
		)
		(duplicate_pad_numbers_are_jumpers no)
		(fp_line
			(start -0.7874 -0.4064)
			(end 0.7874 -0.4064)
			(stroke
				(width 0.1524)
				(type default)
			)
			(layer "F.SilkS")
		)
		(fp_line
			(start -0.7874 0.4064)
			(end -0.7874 -0.4064)
			(stroke
				(width 0.1524)
				(type default)
			)
			(layer "F.SilkS")
		)
		(fp_line
			(start 0.7874 -0.4064)
			(end 0.7874 0.4064)
			(stroke
				(width 0.1524)
				(type default)
			)
			(layer "F.SilkS")
		)
		(fp_line
			(start 0.7874 0.4064)
			(end -0.7874 0.4064)
			(stroke
				(width 0.1524)
				(type default)
			)
			(layer "F.SilkS")
		)
		(fp_line
			(start -0.67945 -0.305054)
			(end -0.12065 -0.305054)
			(stroke
				(width 0.1)
				(type default)
			)
			(layer "F.Fab")
		)
		(fp_line
			(start -0.67945 0.3048)
			(end -0.67945 -0.305054)
			(stroke
				(width 0.1)
				(type default)
			)
			(layer "F.Fab")
		)
		(fp_line
			(start -0.12065 -0.305054)
			(end -0.12065 -0.2794)
			(stroke
				(width 0.1)
				(type default)
			)
			(layer "F.Fab")
		)
		(fp_line
			(start -0.12065 -0.2794)
			(end 0.12065 -0.2794)
			(stroke
				(width 0.1)
				(type default)
			)
			(layer "F.Fab")
		)
		(fp_line
			(start -0.12065 0.2794)
			(end -0.12065 0.3048)
			(stroke
				(width 0.1)
				(type default)
			)
			(layer "F.Fab")
		)
		(fp_line
			(start -0.12065 0.3048)
			(end -0.67945 0.3048)
			(stroke
				(width 0.1)
				(type default)
			)
			(layer "F.Fab")
		)
		(fp_line
			(start 0.120396 0.2794)
			(end -0.12065 0.2794)
			(stroke
				(width 0.1)
				(type default)
			)
			(layer "F.Fab")
		)
		(fp_line
			(start 0.120396 0.3048)
			(end 0.120396 0.2794)
			(stroke
				(width 0.1)
				(type default)
			)
			(layer "F.Fab")
		)
		(fp_line
			(start 0.12065 -0.3048)
			(end 0.67945 -0.3048)
			(stroke
				(width 0.1)
				(type default)
			)
			(layer "F.Fab")
		)
		(fp_line
			(start 0.12065 -0.2794)
			(end 0.12065 -0.3048)
			(stroke
				(width 0.1)
				(type default)
			)
			(layer "F.Fab")
		)
		(fp_line
			(start 0.67945 -0.3048)
			(end 0.67945 0.3048)
			(stroke
				(width 0.1)
				(type default)
			)
			(layer "F.Fab")
		)
		(fp_line
			(start 0.67945 0.3048)
			(end 0.120396 0.3048)
			(stroke
				(width 0.1)
				(type default)
			)
			(layer "F.Fab")
		)
		(pad "1" smd circle
			(at -0.40005 0)
			(size 0 0)
			(layers "F.Cu" "F.Mask" "F.Paste")
			(net "P3V3_AUX")
		)
		(pad "2" smd circle
			(at 0.40005 0)
			(size 0 0)
			(layers "F.Cu" "F.Mask" "F.Paste")
			(net "SWB_HSC_PWRGD")
		)
	)
	(footprint ""
		(layer "F.Cu")
		(at 369.923822 -360.043222 90)
		(property "Reference" "PR1336"
			(at 0 0 90)
			(layer "F.SilkS")
			(hide yes)
			(effects
				(font
					(size 1.27 1.27)
				)
			)
		)
		(property "Value" ""
			(at 0 0 90)
			(layer "F.Fab")
			(effects
				(font
					(size 1.27 1.27)
				)
			)
		)
		(duplicate_pad_numbers_are_jumpers no)
		(fp_line
			(start 0.7874 -0.4064)
			(end 0.7874 0.4064)
			(stroke
				(width 0.1524)
				(type default)
			)
			(layer "F.SilkS")
		)
		(fp_line
			(start -0.7874 -0.4064)
			(end 0.7874 -0.4064)
			(stroke
				(width 0.1524)
				(type default)
			)
			(layer "F.SilkS")
		)
		(fp_line
			(start 0.7874 0.4064)
			(end -0.7874 0.4064)
			(stroke
				(width 0.1524)
				(type default)
			)
			(layer "F.SilkS")
		)
		(fp_line
			(start -0.7874 0.4064)
			(end -0.7874 -0.4064)
			(stroke
				(width 0.1524)
				(type default)
			)
			(layer "F.SilkS")
		)
		(fp_line
			(start -0.12065 -0.305054)
			(end -0.12065 -0.2794)
			(stroke
				(width 0.1)
				(type default)
			)
			(layer "F.Fab")
		)
		(fp_line
			(start -0.67945 -0.305054)
			(end -0.12065 -0.305054)
			(stroke
				(width 0.1)
				(type default)
			)
			(layer "F.Fab")
		)
		(fp_line
			(start 0.67945 -0.3048)
			(end 0.67945 0.3048)
			(stroke
				(width 0.1)
				(type default)
			)
			(layer "F.Fab")
		)
		(fp_line
			(start 0.12065 -0.3048)
			(end 0.67945 -0.3048)
			(stroke
				(width 0.1)
				(type default)
			)
			(layer "F.Fab")
		)
		(fp_line
			(start 0.12065 -0.2794)
			(end 0.12065 -0.3048)
			(stroke
				(width 0.1)
				(type default)
			)
			(layer "F.Fab")
		)
		(fp_line
			(start -0.12065 -0.2794)
			(end 0.12065 -0.2794)
			(stroke
				(width 0.1)
				(type default)
			)
			(layer "F.Fab")
		)
		(fp_line
			(start 0.120396 0.2794)
			(end -0.12065 0.2794)
			(stroke
				(width 0.1)
				(type default)
			)
			(layer "F.Fab")
		)
		(fp_line
			(start -0.12065 0.2794)
			(end -0.12065 0.3048)
			(stroke
				(width 0.1)
				(type default)
			)
			(layer "F.Fab")
		)
		(fp_line
			(start 0.67945 0.3048)
			(end 0.120396 0.3048)
			(stroke
				(width 0.1)
				(type default)
			)
			(layer "F.Fab")
		)
		(fp_line
			(start 0.120396 0.3048)
			(end 0.120396 0.2794)
			(stroke
				(width 0.1)
				(type default)
			)
			(layer "F.Fab")
		)
		(fp_line
			(start -0.12065 0.3048)
			(end -0.67945 0.3048)
			(stroke
				(width 0.1)
				(type default)
			)
			(layer "F.Fab")
		)
		(fp_line
			(start -0.67945 0.3048)
			(end -0.67945 -0.305054)
			(stroke
				(width 0.1)
				(type default)
			)
			(layer "F.Fab")
		)
		(pad "1" smd circle
			(at -0.40005 0 90)
			(size 0 0)
			(layers "F.Cu" "F.Mask" "F.Paste")
			(net "PVPP_HBM_CPU0_CS")
		)
		(pad "2" smd circle
			(at 0.40005 0 90)
			(size 0 0)
			(layers "F.Cu" "F.Mask" "F.Paste")
			(net "GND")
		)
	)
	(footprint ""
		(layer "F.Cu")
		(at 370.615718 -413.90443 -90)
		(property "Reference" "R4199"
			(at 0 0 270)
			(layer "F.SilkS")
			(hide yes)
			(effects
				(font
					(size 1.27 1.27)
				)
			)
		)
		(property "Value" ""
			(at 0 0 270)
			(layer "F.Fab")
			(effects
				(font
					(size 1.27 1.27)
				)
			)
		)
		(duplicate_pad_numbers_are_jumpers no)
		(fp_line
			(start -0.7874 0.4064)
			(end -0.7874 -0.4064)
			(stroke
				(width 0.1524)
				(type default)
			)
			(layer "F.SilkS")
		)
		(fp_line
			(start 0.7874 0.4064)
			(end -0.7874 0.4064)
			(stroke
				(width 0.1524)
				(type default)
			)
			(layer "F.SilkS")
		)
		(fp_line
			(start -0.7874 -0.4064)
			(end 0.7874 -0.4064)
			(stroke
				(width 0.1524)
				(type default)
			)
			(layer "F.SilkS")
		)
		(fp_line
			(start 0.7874 -0.4064)
			(end 0.7874 0.4064)
			(stroke
				(width 0.1524)
				(type default)
			)
			(layer "F.SilkS")
		)
		(fp_line
			(start -0.67945 0.3048)
			(end -0.67945 -0.305054)
			(stroke
				(width 0.1)
				(type default)
			)
			(layer "F.Fab")
		)
		(fp_line
			(start -0.12065 0.3048)
			(end -0.67945 0.3048)
			(stroke
				(width 0.1)
				(type default)
			)
			(layer "F.Fab")
		)
		(fp_line
			(start 0.120396 0.3048)
			(end 0.120396 0.2794)
			(stroke
				(width 0.1)
				(type default)
			)
			(layer "F.Fab")
		)
		(fp_line
			(start 0.67945 0.3048)
			(end 0.120396 0.3048)
			(stroke
				(width 0.1)
				(type default)
			)
			(layer "F.Fab")
		)
		(fp_line
			(start -0.12065 0.2794)
			(end -0.12065 0.3048)
			(stroke
				(width 0.1)
				(type default)
			)
			(layer "F.Fab")
		)
		(fp_line
			(start 0.120396 0.2794)
			(end -0.12065 0.2794)
			(stroke
				(width 0.1)
				(type default)
			)
			(layer "F.Fab")
		)
		(fp_line
			(start -0.12065 -0.2794)
			(end 0.12065 -0.2794)
			(stroke
				(width 0.1)
				(type default)
			)
			(layer "F.Fab")
		)
		(fp_line
			(start 0.12065 -0.2794)
			(end 0.12065 -0.3048)
			(stroke
				(width 0.1)
				(type default)
			)
			(layer "F.Fab")
		)
		(fp_line
			(start 0.12065 -0.3048)
			(end 0.67945 -0.3048)
			(stroke
				(width 0.1)
				(type default)
			)
			(layer "F.Fab")
		)
		(fp_line
			(start 0.67945 -0.3048)
			(end 0.67945 0.3048)
			(stroke
				(width 0.1)
				(type default)
			)
			(layer "F.Fab")
		)
		(fp_line
			(start -0.67945 -0.305054)
			(end -0.12065 -0.305054)
			(stroke
				(width 0.1)
				(type default)
			)
			(layer "F.Fab")
		)
		(fp_line
			(start -0.12065 -0.305054)
			(end -0.12065 -0.2794)
			(stroke
				(width 0.1)
				(type default)
			)
			(layer "F.Fab")
		)
		(pad "1" smd circle
			(at -0.40005 0 270)
			(size 0 0)
			(layers "F.Cu" "F.Mask" "F.Paste")
			(net "U270_0_ADD1")
		)
		(pad "2" smd circle
			(at 0.40005 0 270)
			(size 0 0)
			(layers "F.Cu" "F.Mask" "F.Paste")
			(net "GND")
		)
	)
	(footprint ""
		(layer "F.Cu")
		(at 400.558 -164.785548)
		(property "Reference" "PC1645"
			(at 0 0 0)
			(layer "F.SilkS")
			(hide yes)
			(effects
				(font
					(size 1.27 1.27)
				)
			)
		)
		(property "Value" ""
			(at 0 0 0)
			(layer "F.Fab")
			(effects
				(font
					(size 1.27 1.27)
				)
			)
		)
		(duplicate_pad_numbers_are_jumpers no)
		(fp_line
			(start 2.750058 0.999998)
			(end -2.750058 0.999998)
			(stroke
				(width 0.1524)
				(type default)
			)
			(layer "F.SilkS")
		)
		(fp_circle
			(center 0 0.999998)
			(end 2.750058 0.999998)
			(stroke
				(width 0.1524)
				(type default)
			)
			(fill no)
			(layer "F.SilkS")
		)
		(fp_poly
			(pts
				(arc
					(start 2.750058 0.999998)
					(mid 0 3.750056)
					(end -2.750058 0.999998)
				)
			)
			(stroke
				(width 0)
				(type default)
			)
			(fill yes)
			(layer "F.SilkS")
		)
		(fp_circle
			(center 0 0.999998)
			(end 2.750058 0.999998)
			(stroke
				(width 0.1)
				(type default)
			)
			(fill no)
			(layer "F.Fab")
		)
		(pad "1" thru_hole rect
			(at 0 0)
			(size 1.5748 1.5748)
			(drill 1.0668)
			(layers "*.Cu" "*.Mask")
			(remove_unused_layers no)
			(net "PVCCD_HV_CPU0")
			(clearance 0)
			(padstack
				(mode front_inner_back)
				(layer "Inner"
					(shape circle)
					(size 1.5748 1.5748)
					(clearance 0)
				)
				(layer "B.Cu"
					(shape rect)
					(size 1.5748 1.5748)
					(clearance 0)
				)
			)
		)
		(pad "2" thru_hole circle
			(at 0 1.999996)
			(size 1.5748 1.5748)
			(drill 1.0668)
			(layers "*.Cu" "*.Mask")
			(remove_unused_layers no)
			(net "GND")
			(clearance 0)
		)
	)
)
